# S9S_MB_2U (Grand Teton) — schematic netlist excerpt (pin names and nets, part order shuffled) for the footprints in the layout excerpt that follows; sources: Cadence DE-HDL packaged netlist, KiCad conversion of 03242023_DA0F0TMBIJ0_F0T_Motherboard_J_brd_V01_OCP.brd

PC528_P1_3  Q_CAP  3300PF 50V 10% X7R  pkg 0402  page 286 : A = SW_P12V_PVCCIN_CPU1_FLT ; B = GND
PR1326  Q_RES  0 5% CHIP  pkg 0402LF  page 262 : A = P3V3_AUX ; B = P1V05_PCH_AUX_VCC

(kicad_pcb
	(version 20260206)
	(generator "pcbnew")
	(generator_version "10.0")
	(general
		(thickness 1.6)
		(legacy_teardrops no)
	)
	(paper "A4")
	(title_block
		(title "03242023_DA0F0TMBIJ0_F0T_Motherboard_J_brd_V01_OCP.brd")
		(comment 1 "Grand Teton / footprints 204-205 of 6105")
	)
	(layers
		(0 "F.Cu" signal "TOP")
		(4 "In1.Cu" signal "GND")
		(6 "In2.Cu" signal "IN1")
		(8 "In3.Cu" signal "GND1")
		(10 "In4.Cu" signal "IN2")
		(12 "In5.Cu" signal "GND2")
		(14 "In6.Cu" signal "IN3")
		(16 "In7.Cu" signal "GND3")
		(18 "In8.Cu" signal "VCC")
		(20 "In9.Cu" signal "VCC1")
		(22 "In10.Cu" signal "GND4")
		(24 "In11.Cu" signal "IN4")
		(26 "In12.Cu" signal "GND5")
		(28 "In13.Cu" signal "IN5")
		(30 "In14.Cu" signal "GND6")
		(32 "In15.Cu" signal "IN6")
		(34 "In16.Cu" signal "GND7")
		(2 "B.Cu" signal "BOTTOM")
		(9 "F.Adhes" user "F.Adhesive")
		(11 "B.Adhes" user "B.Adhesive")
		(13 "F.Paste" user "Package Geometry/Pastemask Top")
		(15 "B.Paste" user "Package Geometry/Pastemask Bottom")
		(5 "F.SilkS" user "Ref Des/Silkscreen Top")
		(7 "B.SilkS" user "Ref Des/Silkscreen Bottom")
		(1 "F.Mask" user "Board Geometry/Soldermask Top")
		(3 "B.Mask" user "Board Geometry/Soldermask Bottom")
		(17 "Dwgs.User" user "User.Drawings")
		(19 "Cmts.User" user "User.Comments")
		(21 "Eco1.User" user "User.Eco1")
		(23 "Eco2.User" user "User.Eco2")
		(25 "Edge.Cuts" user "Board Geometry/Outline")
		(27 "Margin" user)
		(31 "F.CrtYd" user "Package Geometry/Place Bound Top")
		(29 "B.CrtYd" user "Package Geometry/Place Bound Bottom")
		(35 "F.Fab" user "Ref Des/Assembly Top")
		(33 "B.Fab" user "Ref Des/Assembly Bottom")
	)
	(footprint ""
		(layer "F.Cu")
		(at 263.101582 -67.08902)
		(property "Reference" "PR1326"
			(at 0 0 0)
			(layer "F.SilkS")
			(hide yes)
			(effects
				(font
					(size 1.27 1.27)
				)
			)
		)
		(property "Value" ""
			(at 0 0 0)
			(layer "F.Fab")
			(effects
				(font
					(size 1.27 1.27)
				)
			)
		)
		(duplicate_pad_numbers_are_jumpers no)
		(fp_line
			(start -0.7874 -0.4064)
			(end 0.7874 -0.4064)
			(stroke
				(width 0.1524)
				(type default)
			)
			(layer "F.SilkS")
		)
		(fp_line
			(start -0.7874 0.4064)
			(end -0.7874 -0.4064)
			(stroke
				(width 0.1524)
				(type default)
			)
			(layer "F.SilkS")
		)
		(fp_line
			(start 0.7874 -0.4064)
			(end 0.7874 0.4064)
			(stroke
				(width 0.1524)
				(type default)
			)
			(layer "F.SilkS")
		)
		(fp_line
			(start 0.7874 0.4064)
			(end -0.7874 0.4064)
			(stroke
				(width 0.1524)
				(type default)
			)
			(layer "F.SilkS")
		)
		(fp_line
			(start -0.67945 -0.305054)
			(end -0.12065 -0.305054)
			(stroke
				(width 0.1)
				(type default)
			)
			(layer "F.Fab")
		)
		(fp_line
			(start -0.67945 0.3048)
			(end -0.67945 -0.305054)
			(stroke
				(width 0.1)
				(type default)
			)
			(layer "F.Fab")
		)
		(fp_line
			(start -0.12065 -0.305054)
			(end -0.12065 -0.2794)
			(stroke
				(width 0.1)
				(type default)
			)
			(layer "F.Fab")
		)
		(fp_line
			(start -0.12065 -0.2794)
			(end 0.12065 -0.2794)
			(stroke
				(width 0.1)
				(type default)
			)
			(layer "F.Fab")
		)
		(fp_line
			(start -0.12065 0.2794)
			(end -0.12065 0.3048)
			(stroke
				(width 0.1)
				(type default)
			)
			(layer "F.Fab")
		)
		(fp_line
			(start -0.12065 0.3048)
			(end -0.67945 0.3048)
			(stroke
				(width 0.1)
				(type default)
			)
			(layer "F.Fab")
		)
		(fp_line
			(start 0.120396 0.2794)
			(end -0.12065 0.2794)
			(stroke
				(width 0.1)
				(type default)
			)
			(layer "F.Fab")
		)
		(fp_line
			(start 0.120396 0.3048)
			(end 0.120396 0.2794)
			(stroke
				(width 0.1)
				(type default)
			)
			(layer "F.Fab")
		)
		(fp_line
			(start 0.12065 -0.3048)
			(end 0.67945 -0.3048)
			(stroke
				(width 0.1)
				(type default)
			)
			(layer "F.Fab")
		)
		(fp_line
			(start 0.12065 -0.2794)
			(end 0.12065 -0.3048)
			(stroke
				(width 0.1)
				(type default)
			)
			(layer "F.Fab")
		)
		(fp_line
			(start 0.67945 -0.3048)
			(end 0.67945 0.3048)
			(stroke
				(width 0.1)
				(type default)
			)
			(layer "F.Fab")
		)
		(fp_line
			(start 0.67945 0.3048)
			(end 0.120396 0.3048)
			(stroke
				(width 0.1)
				(type default)
			)
			(layer "F.Fab")
		)
		(pad "1" smd circle
			(at -0.40005 0)
			(size 0 0)
			(layers "F.Cu" "F.Mask" "F.Paste")
			(net "P3V3_AUX")
		)
		(pad "2" smd circle
			(at 0.40005 0)
			(size 0 0)
			(layers "F.Cu" "F.Mask" "F.Paste")
			(net "P1V05_PCH_AUX_VCC")
		)
	)
	(footprint ""
		(layer "F.Cu")
		(at 117.36832 -337.955382)
		(property "Reference" "PC528_P1_3"
			(at 0 0 0)
			(layer "F.SilkS")
			(hide yes)
			(effects
				(font
					(size 1.27 1.27)
				)
			)
		)
		(property "Value" ""
			(at 0 0 0)
			(layer "F.Fab")
			(effects
				(font
					(size 1.27 1.27)
				)
			)
		)
		(duplicate_pad_numbers_are_jumpers no)
		(fp_line
			(start -0.7874 -0.4064)
			(end 0.7874 -0.4064)
			(stroke
				(width 0.1524)
				(type default)
			)
			(layer "F.SilkS")
		)
		(fp_line
			(start -0.7874 0.4064)
			(end -0.7874 -0.4064)
			(stroke
				(width 0.1524)
				(type default)
			)
			(layer "F.SilkS")
		)
		(fp_line
			(start 0.7874 -0.4064)
			(end 0.7874 0.4064)
			(stroke
				(width 0.1524)
				(type default)
			)
			(layer "F.SilkS")
		)
		(fp_line
			(start 0.7874 0.4064)
			(end -0.7874 0.4064)
			(stroke
				(width 0.1524)
				(type default)
			)
			(layer "F.SilkS")
		)
		(fp_line
			(start -0.67945 -0.305054)
			(end -0.12065 -0.305054)
			(stroke
				(width 0.1)
				(type default)
			)
			(layer "F.Fab")
		)
		(fp_line
			(start -0.67945 0.3048)
			(end -0.67945 -0.305054)
			(stroke
				(width 0.1)
				(type default)
			)
			(layer "F.Fab")
		)
		(fp_line
			(start -0.12065 -0.305054)
			(end -0.12065 -0.2794)
			(stroke
				(width 0.1)
				(type default)
			)
			(layer "F.Fab")
		)
		(fp_line
			(start -0.12065 -0.2794)
			(end 0.12065 -0.2794)
			(stroke
				(width 0.1)
				(type default)
			)
			(layer "F.Fab")
		)
		(fp_line
			(start -0.12065 0.2794)
			(end -0.12065 0.3048)
			(stroke
				(width 0.1)
				(type default)
			)
			(layer "F.Fab")
		)
		(fp_line
			(start -0.12065 0.3048)
			(end -0.67945 0.3048)
			(stroke
				(width 0.1)
				(type default)
			)
			(layer "F.Fab")
		)
		(fp_line
			(start 0.120396 0.2794)
			(end -0.12065 0.2794)
			(stroke
				(width 0.1)
				(type default)
			)
			(layer "F.Fab")
		)
		(fp_line
			(start 0.120396 0.3048)
			(end 0.120396 0.2794)
			(stroke
				(width 0.1)
				(type default)
			)
			(layer "F.Fab")
		)
		(fp_line
			(start 0.12065 -0.3048)
			(end 0.67945 -0.3048)
			(stroke
				(width 0.1)
				(type default)
			)
			(layer "F.Fab")
		)
		(fp_line
			(start 0.12065 -0.2794)
			(end 0.12065 -0.3048)
			(stroke
				(width 0.1)
				(type default)
			)
			(layer "F.Fab")
		)
		(fp_line
			(start 0.67945 -0.3048)
			(end 0.67945 0.3048)
			(stroke
				(width 0.1)
				(type default)
			)
			(layer "F.Fab")
		)
		(fp_line
			(start 0.67945 0.3048)
			(end 0.120396 0.3048)
			(stroke
				(width 0.1)
				(type default)
			)
			(layer "F.Fab")
		)
		(pad "1" smd circle
			(at -0.40005 0)
			(size 0 0)
			(layers "F.Cu" "F.Mask" "F.Paste")
			(net "SW_P12V_PVCCIN_CPU1_FLT")
		)
		(pad "2" smd circle
			(at 0.40005 0)
			(size 0 0)
			(layers "F.Cu" "F.Mask" "F.Paste")
			(net "GND")
		)
	)
)
